(kicad_pcb
	(version 20260206)
	(generator "pcbnew")
	(generator_version "10.0")
	(general
		(thickness 1.6)
		(legacy_teardrops no)
	)
	(paper "A4")
	(title_block
		(title "04192023_DAF0TMB3IC0_F0TG_MB_C_brd_V02_OCP.brd")
		(comment 1 "Grand Teton / footprints 1168-1171 of 8354")
	)
	(layers
		(0 "F.Cu" signal "TOP")
		(4 "In1.Cu" signal "GND")
		(6 "In2.Cu" signal "IN1")
		(8 "In3.Cu" signal "GND1")
		(10 "In4.Cu" signal "IN2")
		(12 "In5.Cu" signal "GND2")
		(14 "In6.Cu" signal "IN3")
		(16 "In7.Cu" signal "GND3")
		(18 "In8.Cu" signal "VCC")
		(20 "In9.Cu" signal "VCC1")
		(22 "In10.Cu" signal "GND4")
		(24 "In11.Cu" signal "IN4")
		(26 "In12.Cu" signal "GND5")
		(28 "In13.Cu" signal "IN5")
		(30 "In14.Cu" signal "GND6")
		(32 "In15.Cu" signal "IN6")
		(34 "In16.Cu" signal "GND7")
		(2 "B.Cu" signal "BOTTOM")
		(9 "F.Adhes" user "F.Adhesive")
		(11 "B.Adhes" user "B.Adhesive")
		(13 "F.Paste" user "Package Geometry/Pastemask Top")
		(15 "B.Paste" user "Package Geometry/Pastemask Bottom")
		(5 "F.SilkS" user "Ref Des/Silkscreen Top")
		(7 "B.SilkS" user "Ref Des/Silkscreen Bottom")
		(1 "F.Mask" user "Board Geometry/Soldermask Top")
		(3 "B.Mask" user "Board Geometry/Soldermask Bottom")
		(17 "Dwgs.User" user "User.Drawings")
		(19 "Cmts.User" user "User.Comments")
		(21 "Eco1.User" user "User.Eco1")
		(23 "Eco2.User" user "User.Eco2")
		(25 "Edge.Cuts" user "Board Geometry/Outline")
		(27 "Margin" user)
		(31 "F.CrtYd" user "Package Geometry/Place Bound Top")
		(29 "B.CrtYd" user "Package Geometry/Place Bound Bottom")
		(35 "F.Fab" user "Ref Des/Assembly Top")
		(33 "B.Fab" user "Ref Des/Assembly Bottom")
	)
	(footprint ""
		(layer "F.Cu")
		(at 13.546582 -134.039102)
		(property "Reference" "U247"
			(at -2.7432 -3.012948 0)
			(unlocked yes)
			(layer "F.SilkS")
			(effects
				(font
					(size 0.7874 0.5842)
					(thickness 0.1524)
				)
				(justify left)
			)
		)
		(property "Value" ""
			(at 0 0 0)
			(layer "F.Fab")
			(effects
				(font
					(size 1.27 1.27)
				)
			)
		)
		(duplicate_pad_numbers_are_jumpers no)
		(fp_line
			(start -2.050034 -2.050034)
			(end -2.050034 -1.516634)
			(stroke
				(width 0.1524)
				(type default)
			)
			(layer "F.SilkS")
		)
		(fp_line
			(start -2.050034 1.516634)
			(end -2.050034 2.050034)
			(stroke
				(width 0.1524)
				(type default)
			)
			(layer "F.SilkS")
		)
		(fp_line
			(start -2.050034 2.050034)
			(end -1.516634 2.050034)
			(stroke
				(width 0.1524)
				(type default)
			)
			(layer "F.SilkS")
		)
		(fp_line
			(start -1.516634 -2.050034)
			(end -2.050034 -2.050034)
			(stroke
				(width 0.1524)
				(type default)
			)
			(layer "F.SilkS")
		)
		(fp_line
			(start 1.516634 2.050034)
			(end 2.050034 2.050034)
			(stroke
				(width 0.1524)
				(type default)
			)
			(layer "F.SilkS")
		)
		(fp_line
			(start 2.050034 -2.050034)
			(end 1.516634 -2.050034)
			(stroke
				(width 0.1524)
				(type default)
			)
			(layer "F.SilkS")
		)
		(fp_line
			(start 2.050034 -1.516634)
			(end 2.050034 -2.050034)
			(stroke
				(width 0.1524)
				(type default)
			)
			(layer "F.SilkS")
		)
		(fp_line
			(start 2.050034 2.050034)
			(end 2.050034 1.516634)
			(stroke
				(width 0.1524)
				(type default)
			)
			(layer "F.SilkS")
		)
		(fp_poly
			(pts
				(xy -2.634234 -1.542034) (xy -2.050034 -1.542034) (xy -2.050034 -2.126234) (xy -2.634234 -2.126234)
			)
			(stroke
				(width 0)
				(type default)
			)
			(fill yes)
			(layer "F.SilkS")
		)
		(fp_line
			(start -2.050034 -2.050034)
			(end -2.050034 2.050034)
			(stroke
				(width 0.1)
				(type default)
			)
			(layer "F.Fab")
		)
		(fp_line
			(start -2.050034 2.050034)
			(end 2.050034 2.050034)
			(stroke
				(width 0.1)
				(type default)
			)
			(layer "F.Fab")
		)
		(fp_line
			(start 2.050034 -2.050034)
			(end -2.050034 -2.050034)
			(stroke
				(width 0.1)
				(type default)
			)
			(layer "F.Fab")
		)
		(fp_line
			(start 2.050034 2.050034)
			(end 2.050034 -2.050034)
			(stroke
				(width 0.1)
				(type default)
			)
			(layer "F.Fab")
		)
		(fp_poly
			(pts
				(xy -2.634234 -1.542034) (xy -2.050034 -1.542034) (xy -2.050034 -2.126234) (xy -2.634234 -2.126234)
			)
			(stroke
				(width 0)
				(type default)
			)
			(fill yes)
			(layer "F.Fab")
		)
		(pad "1" smd rect
			(at -1.875028 -1.249934 270)
			(size 0.254 0.5588)
			(layers "F.Cu" "F.Mask" "F.Paste")
			(net "CLK_GEN2_XTAL_IN")
		)
		(pad "2" smd rect
			(at -1.875028 -0.750062 270)
			(size 0.254 0.5588)
			(layers "F.Cu" "F.Mask" "F.Paste")
			(net "CLK_GEN2_XTAL_OUT")
		)
		(pad "3" smd rect
			(at -1.875028 -0.249936 270)
			(size 0.254 0.5588)
			(layers "F.Cu" "F.Mask" "F.Paste")
			(net "VFG3P3_CLK_GEN")
		)
		(pad "4" smd rect
			(at -1.875028 0.249936 270)
			(size 0.254 0.5588)
			(layers "F.Cu" "F.Mask" "F.Paste")
			(net "CLK_GEN2_SMB_SADR")
		)
		(pad "5" smd rect
			(at -1.875028 0.750062 270)
			(size 0.254 0.5588)
			(layers "F.Cu" "F.Mask" "F.Paste")
			(net "GND")
		)
		(pad "6" smd rect
			(at -1.875028 1.249934 270)
			(size 0.254 0.5588)
			(layers "F.Cu" "F.Mask" "F.Paste")
			(net "GND")
		)
		(pad "7" smd rect
			(at -1.249934 1.875028)
			(size 0.254 0.5588)
			(layers "F.Cu" "F.Mask" "F.Paste")
			(net "VFG3P3_CLK_GEN")
		)
		(pad "8" smd rect
			(at -0.750062 1.875028)
			(size 0.254 0.5588)
			(layers "F.Cu" "F.Mask" "F.Paste")
			(net "SMB_HOST_CLK_GEN2_3V3AUX_SCL")
		)
		(pad "9" smd rect
			(at -0.249936 1.875028)
			(size 0.254 0.5588)
			(layers "F.Cu" "F.Mask" "F.Paste")
			(net "SMB_HOST_CLK_GEN2_3V3AUX_SDA")
		)
		(pad "10" smd rect
			(at 0.249936 1.875028)
			(size 0.254 0.5588)
			(layers "F.Cu" "F.Mask" "F.Paste")
			(net "GND")
		)
		(pad "11" smd rect
			(at 0.750062 1.875028)
			(size 0.254 0.5588)
			(layers "F.Cu" "F.Mask" "F.Paste")
			(net "VFG3P3_CLK_GEN")
		)
		(pad "12" smd rect
			(at 1.249934 1.875028)
			(size 0.254 0.5588)
			(layers "F.Cu" "F.Mask" "F.Paste")
			(net "CLK_GEN2_BMC_RC_OE_R3_N")
		)
		(pad "13" smd rect
			(at 1.875028 1.249934 270)
			(size 0.254 0.5588)
			(layers "F.Cu" "F.Mask" "F.Paste")
			(net "CLK_100M_BMC_RC_DP_R")
		)
		(pad "14" smd rect
			(at 1.875028 0.750062 270)
			(size 0.254 0.5588)
			(layers "F.Cu" "F.Mask" "F.Paste")
			(net "CLK_100M_BMC_RC_DN_R")
		)
		(pad "15" smd rect
			(at 1.875028 0.249936 270)
			(size 0.254 0.5588)
			(layers "F.Cu" "F.Mask" "F.Paste")
			(net "GND")
		)
		(pad "16" smd rect
			(at 1.875028 -0.249936 270)
			(size 0.254 0.5588)
			(layers "F.Cu" "F.Mask" "F.Paste")
			(net "VFG_3P3A_CLK_GEN")
		)
		(pad "17" smd rect
			(at 1.875028 -0.750062 270)
			(size 0.254 0.5588)
			(layers "F.Cu" "F.Mask" "F.Paste")
			(net "CLK_100M_GPU_FPGA_DP_R")
		)
		(pad "18" smd rect
			(at 1.875028 -1.249934 270)
			(size 0.254 0.5588)
			(layers "F.Cu" "F.Mask" "F.Paste")
			(net "CLK_100M_GPU_FPGA_DN_R")
		)
		(pad "19" smd rect
			(at 1.249934 -1.875028)
			(size 0.254 0.5588)
			(layers "F.Cu" "F.Mask" "F.Paste")
			(net "CLK_GEN2_GPU_OE_N")
		)
		(pad "20" smd rect
			(at 0.750062 -1.875028)
			(size 0.254 0.5588)
			(layers "F.Cu" "F.Mask" "F.Paste")
			(net "VFG3P3_CLK_GEN")
		)
		(pad "21" smd rect
			(at 0.249936 -1.875028)
			(size 0.254 0.5588)
			(layers "F.Cu" "F.Mask" "F.Paste")
			(net "GND")
		)
		(pad "22" smd rect
			(at -0.249936 -1.875028)
			(size 0.254 0.5588)
			(layers "F.Cu" "F.Mask" "F.Paste")
			(net "P3V3_PWRGD_CLKGEN")
		)
		(pad "23" smd rect
			(at -0.750062 -1.875028)
			(size 0.254 0.5588)
			(layers "F.Cu" "F.Mask" "F.Paste")
			(net "FG_SS_EN")
		)
		(pad "24" smd rect
			(at -1.249934 -1.875028)
			(size 0.254 0.5588)
			(layers "F.Cu" "F.Mask" "F.Paste")
			(net "GND")
		)
		(pad "25" smd circle
			(at 0 0)
			(size 0 0)
			(layers "F.Cu" "F.Mask" "F.Paste")
			(net "GND")
		)
	)
	(footprint ""
		(layer "F.Cu")
		(at 419.230302 -434.386736 90)
		(property "Reference" "R4167"
			(at 0 0 90)
			(layer "F.SilkS")
			(hide yes)
			(effects
				(font
					(size 1.27 1.27)
				)
			)
		)
		(property "Value" ""
			(at 0 0 90)
			(layer "F.Fab")
			(effects
				(font
					(size 1.27 1.27)
				)
			)
		)
		(duplicate_pad_numbers_are_jumpers no)
		(fp_line
			(start 0.7874 -0.4064)
			(end 0.7874 0.4064)
			(stroke
				(width 0.1524)
				(type default)
			)
			(layer "F.SilkS")
		)
		(fp_line
			(start -0.7874 -0.4064)
			(end 0.7874 -0.4064)
			(stroke
				(width 0.1524)
				(type default)
			)
			(layer "F.SilkS")
		)
		(fp_line
			(start 0.7874 0.4064)
			(end -0.7874 0.4064)
			(stroke
				(width 0.1524)
				(type default)
			)
			(layer "F.SilkS")
		)
		(fp_line
			(start -0.7874 0.4064)
			(end -0.7874 -0.4064)
			(stroke
				(width 0.1524)
				(type default)
			)
			(layer "F.SilkS")
		)
		(fp_line
			(start -0.12065 -0.305054)
			(end -0.12065 -0.2794)
			(stroke
				(width 0.1)
				(type default)
			)
			(layer "F.Fab")
		)
		(fp_line
			(start -0.67945 -0.305054)
			(end -0.12065 -0.305054)
			(stroke
				(width 0.1)
				(type default)
			)
			(layer "F.Fab")
		)
		(fp_line
			(start 0.67945 -0.3048)
			(end 0.67945 0.3048)
			(stroke
				(width 0.1)
				(type default)
			)
			(layer "F.Fab")
		)
		(fp_line
			(start 0.12065 -0.3048)
			(end 0.67945 -0.3048)
			(stroke
				(width 0.1)
				(type default)
			)
			(layer "F.Fab")
		)
		(fp_line
			(start 0.12065 -0.2794)
			(end 0.12065 -0.3048)
			(stroke
				(width 0.1)
				(type default)
			)
			(layer "F.Fab")
		)
		(fp_line
			(start -0.12065 -0.2794)
			(end 0.12065 -0.2794)
			(stroke
				(width 0.1)
				(type default)
			)
			(layer "F.Fab")
		)
		(fp_line
			(start 0.120396 0.2794)
			(end -0.12065 0.2794)
			(stroke
				(width 0.1)
				(type default)
			)
			(layer "F.Fab")
		)
		(fp_line
			(start -0.12065 0.2794)
			(end -0.12065 0.3048)
			(stroke
				(width 0.1)
				(type default)
			)
			(layer "F.Fab")
		)
		(fp_line
			(start 0.67945 0.3048)
			(end 0.120396 0.3048)
			(stroke
				(width 0.1)
				(type default)
			)
			(layer "F.Fab")
		)
		(fp_line
			(start 0.120396 0.3048)
			(end 0.120396 0.2794)
			(stroke
				(width 0.1)
				(type default)
			)
			(layer "F.Fab")
		)
		(fp_line
			(start -0.12065 0.3048)
			(end -0.67945 0.3048)
			(stroke
				(width 0.1)
				(type default)
			)
			(layer "F.Fab")
		)
		(fp_line
			(start -0.67945 0.3048)
			(end -0.67945 -0.305054)
			(stroke
				(width 0.1)
				(type default)
			)
			(layer "F.Fab")
		)
		(pad "1" smd circle
			(at -0.40005 0 90)
			(size 0 0)
			(layers "F.Cu" "F.Mask" "F.Paste")
			(net "P3V3_AUX")
		)
		(pad "2" smd circle
			(at 0.40005 0 90)
			(size 0 0)
			(layers "F.Cu" "F.Mask" "F.Paste")
			(net "GPU_3V3IO_RSVD1_ISO")
		)
	)
	(footprint ""
		(layer "F.Cu")
		(at 66.372994 -36.800028)
		(property "Reference" "R6060"
			(at 0 0 0)
			(layer "F.SilkS")
			(hide yes)
			(effects
				(font
					(size 1.27 1.27)
				)
			)
		)
		(property "Value" ""
			(at 0 0 0)
			(layer "F.Fab")
			(effects
				(font
					(size 1.27 1.27)
				)
			)
		)
		(duplicate_pad_numbers_are_jumpers no)
		(fp_line
			(start -0.7874 -0.4064)
			(end 0.7874 -0.4064)
			(stroke
				(width 0.1524)
				(type default)
			)
			(layer "F.SilkS")
		)
		(fp_line
			(start -0.7874 0.4064)
			(end -0.7874 -0.4064)
			(stroke
				(width 0.1524)
				(type default)
			)
			(layer "F.SilkS")
		)
		(fp_line
			(start 0.7874 -0.4064)
			(end 0.7874 0.4064)
			(stroke
				(width 0.1524)
				(type default)
			)
			(layer "F.SilkS")
		)
		(fp_line
			(start 0.7874 0.4064)
			(end -0.7874 0.4064)
			(stroke
				(width 0.1524)
				(type default)
			)
			(layer "F.SilkS")
		)
		(fp_line
			(start -0.67945 -0.305054)
			(end -0.12065 -0.305054)
			(stroke
				(width 0.1)
				(type default)
			)
			(layer "F.Fab")
		)
		(fp_line
			(start -0.67945 0.3048)
			(end -0.67945 -0.305054)
			(stroke
				(width 0.1)
				(type default)
			)
			(layer "F.Fab")
		)
		(fp_line
			(start -0.12065 -0.305054)
			(end -0.12065 -0.2794)
			(stroke
				(width 0.1)
				(type default)
			)
			(layer "F.Fab")
		)
		(fp_line
			(start -0.12065 -0.2794)
			(end 0.12065 -0.2794)
			(stroke
				(width 0.1)
				(type default)
			)
			(layer "F.Fab")
		)
		(fp_line
			(start -0.12065 0.2794)
			(end -0.12065 0.3048)
			(stroke
				(width 0.1)
				(type default)
			)
			(layer "F.Fab")
		)
		(fp_line
			(start -0.12065 0.3048)
			(end -0.67945 0.3048)
			(stroke
				(width 0.1)
				(type default)
			)
			(layer "F.Fab")
		)
		(fp_line
			(start 0.120396 0.2794)
			(end -0.12065 0.2794)
			(stroke
				(width 0.1)
				(type default)
			)
			(layer "F.Fab")
		)
		(fp_line
			(start 0.120396 0.3048)
			(end 0.120396 0.2794)
			(stroke
				(width 0.1)
				(type default)
			)
			(layer "F.Fab")
		)
		(fp_line
			(start 0.12065 -0.3048)
			(end 0.67945 -0.3048)
			(stroke
				(width 0.1)
				(type default)
			)
			(layer "F.Fab")
		)
		(fp_line
			(start 0.12065 -0.2794)
			(end 0.12065 -0.3048)
			(stroke
				(width 0.1)
				(type default)
			)
			(layer "F.Fab")
		)
		(fp_line
			(start 0.67945 -0.3048)
			(end 0.67945 0.3048)
			(stroke
				(width 0.1)
				(type default)
			)
			(layer "F.Fab")
		)
		(fp_line
			(start 0.67945 0.3048)
			(end 0.120396 0.3048)
			(stroke
				(width 0.1)
				(type default)
			)
			(layer "F.Fab")
		)
		(pad "1" smd circle
			(at -0.40005 0)
			(size 0 0)
			(layers "F.Cu" "F.Mask" "F.Paste")
			(net "P12V_OCP_EN_2_R")
		)
		(pad "2" smd circle
			(at 0.40005 0)
			(size 0 0)
			(layers "F.Cu" "F.Mask" "F.Paste")
			(net "GND")
		)
	)
	(footprint ""
		(layer "F.Cu")
		(at 343.43086 -325.670926)
		(property "Reference" "PL15"
			(at -3.115056 -16.014446 0)
			(unlocked yes)
			(layer "F.SilkS")
			(effects
				(font
					(size 0.7874 0.5842)
					(thickness 0.1524)
				)
				(justify left)
			)
		)
		(property "Value" ""
			(at 0 0 0)
			(layer "F.Fab")
			(effects
				(font
					(size 1.27 1.27)
				)
			)
		)
		(duplicate_pad_numbers_are_jumpers no)
		(fp_line
			(start -3.750056 -5.500116)
			(end -2.393442 -5.500116)
			(stroke
				(width 0.1524)
				(type default)
			)
			(layer "F.SilkS")
		)
		(fp_line
			(start -3.750056 5.500116)
			(end -3.750056 -5.500116)
			(stroke
				(width 0.1524)
				(type default)
			)
			(layer "F.SilkS")
		)
		(fp_line
			(start -2.393442 5.500116)
			(end -3.750056 5.500116)
			(stroke
				(width 0.1524)
				(type default)
			)
			(layer "F.SilkS")
		)
		(fp_line
			(start 2.393442 5.500116)
			(end 3.750056 5.500116)
			(stroke
				(width 0.1524)
				(type default)
			)
			(layer "F.SilkS")
		)
		(fp_line
			(start 3.750056 -5.500116)
			(end 2.393442 -5.500116)
			(stroke
				(width 0.1524)
				(type default)
			)
			(layer "F.SilkS")
		)
		(fp_line
			(start 3.750056 5.500116)
			(end 3.750056 -5.500116)
			(stroke
				(width 0.1524)
				(type default)
			)
			(layer "F.SilkS")
		)
		(fp_poly
			(pts
				(xy -3.9116 -4.249928) (xy -4.3434 -4.034028) (xy -4.3434 -4.465828)
			)
			(stroke
				(width 0)
				(type default)
			)
			(fill yes)
			(layer "F.SilkS")
		)
		(fp_line
			(start -3.750056 -5.500116)
			(end -3.750056 5.500116)
			(stroke
				(width 0.1)
				(type default)
			)
			(layer "F.Fab")
		)
		(fp_line
			(start -3.750056 5.500116)
			(end 3.750056 5.500116)
			(stroke
				(width 0.1)
				(type default)
			)
			(layer "F.Fab")
		)
		(fp_line
			(start 3.750056 -5.500116)
			(end -3.750056 -5.500116)
			(stroke
				(width 0.1)
				(type default)
			)
			(layer "F.Fab")
		)
		(fp_line
			(start 3.750056 5.500116)
			(end 3.750056 -5.500116)
			(stroke
				(width 0.1)
				(type default)
			)
			(layer "F.Fab")
		)
		(fp_poly
			(pts
				(xy -4.9276 -4.757928) (xy -4.9276 -3.741928) (xy -3.9116 -4.249928)
			)
			(stroke
				(width 0)
				(type default)
			)
			(fill yes)
			(layer "F.Fab")
		)
		(pad "1" smd rect
			(at 0 -4.249928 270)
			(size 2.413 4.5212)
			(layers "F.Cu" "F.Mask" "F.Paste")
			(net "SW_PVDDCR_CPU1_P0_SW5")
		)
		(pad "2" smd rect
			(at 0 -1.175004 270)
			(size 1.3716 4.5212)
			(layers "F.Cu" "F.Mask" "F.Paste")
			(net "IND_CPU1_P0_CPL6")
		)
		(pad "3" smd rect
			(at 0 1.175004 270)
			(size 1.3716 4.5212)
			(layers "F.Cu" "F.Mask" "F.Paste")
			(net "IND_CPU1_P0_CPL5")
		)
		(pad "4" smd rect
			(at 0 4.249928 270)
			(size 2.413 4.5212)
			(layers "F.Cu" "F.Mask" "F.Paste")
			(net "PVDDCR_CPU1_P0")
		)
	)
)
